# BASEBOARD_FAB2 (Tioga Pass) — schematic netlist excerpt (pin names and nets, part order shuffled) for the footprints in the layout excerpt that follows; sources: Cadence DE-HDL packaged netlist, KiCad conversion of Wiwynn_Tioga_Pass_MB.brd

C1T15  CAP  10UF 6.3V 20% X6S  pkg 0603  page 239 : A = P1V2_AUX_BMC ; B = GND
C7M5  CAP_A  47UF 4V 20% X5R  pkg 0603V  page 228 : A = PVDDQ_KLM ; B = GND
C8L1  CAP  100UF 4V 20% X5R  pkg 0805  page 228 : A = PVDDQ_KLM ; B = GND

(kicad_pcb
	(version 20260206)
	(generator "pcbnew")
	(generator_version "10.0")
	(general
		(thickness 1.6)
		(legacy_teardrops no)
	)
	(paper "A4")
	(title_block
		(title "Wiwynn_Tioga_Pass_MB.brd")
		(comment 1 "Tioga Pass / footprints 4345-4347 of 4770")
	)
	(layers
		(0 "F.Cu" signal "TOP")
		(4 "In1.Cu" signal "L2GND")
		(6 "In2.Cu" signal "L3")
		(8 "In3.Cu" signal "L4GND")
		(10 "In4.Cu" signal "L5")
		(12 "In5.Cu" signal "L6GND")
		(14 "In6.Cu" signal "L7VCC")
		(16 "In7.Cu" signal "L8VCC")
		(18 "In8.Cu" signal "L9GND")
		(20 "In9.Cu" signal "L10")
		(22 "In10.Cu" signal "L11GND")
		(24 "In11.Cu" signal "L12")
		(26 "In12.Cu" signal "L13GND")
		(2 "B.Cu" signal "BOTTOM")
		(9 "F.Adhes" user "F.Adhesive")
		(11 "B.Adhes" user "B.Adhesive")
		(13 "F.Paste" user "Package Geometry/Pastemask Top")
		(15 "B.Paste" user "Package Geometry/Pastemask Bottom")
		(5 "F.SilkS" user "Ref Des/Silkscreen Top")
		(7 "B.SilkS" user "Ref Des/Silkscreen Bottom")
		(1 "F.Mask" user "Board Geometry/Soldermask Top")
		(3 "B.Mask" user "Board Geometry/Soldermask Bottom")
		(17 "Dwgs.User" user "User.Drawings")
		(19 "Cmts.User" user "User.Comments")
		(21 "Eco1.User" user "User.Eco1")
		(23 "Eco2.User" user "User.Eco2")
		(25 "Edge.Cuts" user "Board Geometry/Outline")
		(27 "Margin" user)
		(31 "F.CrtYd" user "Package Geometry/Place Bound Top")
		(29 "B.CrtYd" user "Package Geometry/Place Bound Bottom")
		(35 "F.Fab" user "Ref Des/Assembly Top")
		(33 "B.Fab" user "Ref Des/Assembly Bottom")
	)
	(footprint ""
		(layer "B.Cu")
		(at 106.762296 -156.910024 -90)
		(property "Reference" "C8L1"
			(at 0 0 90)
			(layer "B.SilkS")
			(hide yes)
			(effects
				(font
					(size 1.27 1.27)
				)
				(justify mirror)
			)
		)
		(property "Value" ""
			(at 0 0 90)
			(layer "B.Fab")
			(effects
				(font
					(size 1.27 1.27)
				)
				(justify mirror)
			)
		)
		(duplicate_pad_numbers_are_jumpers no)
		(fp_poly
			(pts
				(xy 0.7239 -0.2159) (xy -0.7239 -0.2159) (xy -0.7239 1.9939) (xy 0.7239 1.9939)
			)
			(stroke
				(width 0)
				(type default)
			)
			(fill no)
			(layer "B.CrtYd")
		)
		(fp_line
			(start -0.7239 1.9939)
			(end -0.7239 -0.2159)
			(stroke
				(width 0.1)
				(type default)
			)
			(layer "B.Fab")
		)
		(fp_line
			(start 0.7239 1.9939)
			(end -0.7239 1.9939)
			(stroke
				(width 0.1)
				(type default)
			)
			(layer "B.Fab")
		)
		(fp_line
			(start -0.7239 -0.2159)
			(end 0.7239 -0.2159)
			(stroke
				(width 0.1)
				(type default)
			)
			(layer "B.Fab")
		)
		(fp_line
			(start 0.7239 -0.2159)
			(end 0.7239 1.9939)
			(stroke
				(width 0.1)
				(type default)
			)
			(layer "B.Fab")
		)
		(pad "1" smd rect
			(at 0 0 90)
			(size 1.27 1.016)
			(layers "B.Cu" "B.Mask" "B.Paste")
			(net "PVDDQ_KLM")
		)
		(pad "2" smd rect
			(at 0 1.778 90)
			(size 1.27 1.016)
			(layers "B.Cu" "B.Mask" "B.Paste")
			(net "GND")
		)
		(zone
			(layer "B.Cu")
			(hatch none 0.5)
			(connect_pads
				(clearance 0)
			)
			(min_thickness 0.25)
			(keepout
				(tracks not_allowed)
				(vias allowed)
				(pads allowed)
				(copperpour not_allowed)
				(footprints allowed)
			)
			(placement
				(enabled no)
				(sheetname "")
			)
			(fill
				(thermal_gap 0.5)
				(thermal_bridge_width 0.5)
				(island_removal_mode 0)
			)
			(polygon
				(pts
					(xy 106.254296 -156.275024) (xy 106.254296 -157.545024) (xy 105.492296 -157.545024) (xy 105.492296 -156.275024)
				)
			)
		)
	)
	(footprint ""
		(layer "B.Cu")
		(at 113.44148 -124.655834 90)
		(property "Reference" "C7M5"
			(at -1.71831 0.57658 0)
			(unlocked yes)
			(layer "B.SilkS")
			(effects
				(font
					(size 0.7874 0.5842)
					(thickness 0.1524)
				)
				(justify mirror)
			)
		)
		(property "Value" ""
			(at 0 0 90)
			(layer "B.Fab")
			(effects
				(font
					(size 1.27 1.27)
				)
				(justify mirror)
			)
		)
		(duplicate_pad_numbers_are_jumpers no)
		(fp_rect
			(start 0.500126 1.598422)
			(end -0.500126 -0.201422)
			(stroke
				(width 0)
				(type default)
			)
			(fill no)
			(layer "B.CrtYd")
		)
		(fp_line
			(start 0.500126 -0.201422)
			(end -0.500126 -0.201422)
			(stroke
				(width 0.1)
				(type default)
			)
			(layer "B.Fab")
		)
		(fp_line
			(start -0.500126 -0.201422)
			(end -0.500126 1.598422)
			(stroke
				(width 0.1)
				(type default)
			)
			(layer "B.Fab")
		)
		(fp_line
			(start 0.500126 1.598422)
			(end 0.500126 -0.201422)
			(stroke
				(width 0.1)
				(type default)
			)
			(layer "B.Fab")
		)
		(fp_line
			(start -0.500126 1.598422)
			(end 0.500126 1.598422)
			(stroke
				(width 0.1)
				(type default)
			)
			(layer "B.Fab")
		)
		(pad "1" smd rect
			(at 0 0)
			(size 0.889 0.9906)
			(layers "B.Cu" "B.Mask" "B.Paste")
			(net "PVDDQ_KLM")
		)
		(pad "2" smd rect
			(at 0 1.397)
			(size 0.889 0.9906)
			(layers "B.Cu" "B.Mask" "B.Paste")
			(net "GND")
		)
		(zone
			(layer "B.Cu")
			(hatch none 0.5)
			(connect_pads
				(clearance 0)
			)
			(min_thickness 0.25)
			(keepout
				(tracks allowed)
				(vias not_allowed)
				(pads allowed)
				(copperpour not_allowed)
				(footprints allowed)
			)
			(placement
				(enabled no)
				(sheetname "")
			)
			(fill
				(thermal_gap 0.5)
				(thermal_bridge_width 0.5)
				(island_removal_mode 0)
			)
			(polygon
				(pts
					(xy 114.39398 -125.151134) (xy 113.88598 -125.151134) (xy 113.88598 -124.160534) (xy 114.39398 -124.160534)
				)
			)
		)
		(zone
			(layer "B.Cu")
			(hatch none 0.5)
			(connect_pads
				(clearance 0)
			)
			(min_thickness 0.25)
			(keepout
				(tracks not_allowed)
				(vias allowed)
				(pads allowed)
				(copperpour not_allowed)
				(footprints allowed)
			)
			(placement
				(enabled no)
				(sheetname "")
			)
			(fill
				(thermal_gap 0.5)
				(thermal_bridge_width 0.5)
				(island_removal_mode 0)
			)
			(polygon
				(pts
					(xy 114.39398 -125.151134) (xy 113.88598 -125.151134) (xy 113.88598 -124.160534) (xy 114.39398 -124.160534)
				)
			)
		)
	)
	(footprint ""
		(layer "B.Cu")
		(at 468.341202 -36.435792 -90)
		(property "Reference" "C1T15"
			(at 0 0 90)
			(layer "B.SilkS")
			(hide yes)
			(effects
				(font
					(size 1.27 1.27)
				)
				(justify mirror)
			)
		)
		(property "Value" ""
			(at 0 0 90)
			(layer "B.Fab")
			(effects
				(font
					(size 1.27 1.27)
				)
				(justify mirror)
			)
		)
		(duplicate_pad_numbers_are_jumpers no)
		(fp_poly
			(pts
				(xy 0.4953 -0.2032) (xy -0.4953 -0.2032) (xy -0.4953 1.6002) (xy 0.4953 1.6002)
			)
			(stroke
				(width 0)
				(type default)
			)
			(fill no)
			(layer "B.CrtYd")
		)
		(fp_line
			(start -0.4953 1.6002)
			(end 0.4953 1.6002)
			(stroke
				(width 0.1)
				(type default)
			)
			(layer "B.Fab")
		)
		(fp_line
			(start 0.4953 1.6002)
			(end 0.4953 -0.2032)
			(stroke
				(width 0.1)
				(type default)
			)
			(layer "B.Fab")
		)
		(fp_line
			(start -0.4953 -0.2032)
			(end -0.4953 1.6002)
			(stroke
				(width 0.1)
				(type default)
			)
			(layer "B.Fab")
		)
		(fp_line
			(start 0.4953 -0.2032)
			(end -0.4953 -0.2032)
			(stroke
				(width 0.1)
				(type default)
			)
			(layer "B.Fab")
		)
		(pad "1" smd rect
			(at 0 0 90)
			(size 0.762 0.889)
			(layers "B.Cu" "B.Mask" "B.Paste")
			(net "P1V2_AUX_BMC")
		)
		(pad "2" smd rect
			(at 0 1.397 90)
			(size 0.762 0.889)
			(layers "B.Cu" "B.Mask" "B.Paste")
			(net "GND")
		)
		(zone
			(layer "B.Cu")
			(hatch none 0.5)
			(connect_pads
				(clearance 0)
			)
			(min_thickness 0.25)
			(keepout
				(tracks not_allowed)
				(vias allowed)
				(pads allowed)
				(copperpour not_allowed)
				(footprints allowed)
			)
			(placement
				(enabled no)
				(sheetname "")
			)
			(fill
				(thermal_gap 0.5)
				(thermal_bridge_width 0.5)
				(island_removal_mode 0)
			)
			(polygon
				(pts
					(xy 467.896702 -36.054792) (xy 467.896702 -36.816792) (xy 467.388702 -36.816792) (xy 467.388702 -36.054792)
				)
			)
		)
	)
)
